(kicad_pcb
	(version 20260206)
	(generator "pcbnew")
	(generator_version "10.0")
	(general
		(thickness 1.6)
		(legacy_teardrops no)
	)
	(paper "A4")
	(title_block
		(title "Bryce Canyon_F.DPB_16315-1-OCP.brd")
		(comment 1 "Bryce Canyon / footprints 2149-2156 of 2223")
	)
	(layers
		(0 "F.Cu" signal "TOP")
		(4 "In1.Cu" signal "L2GND")
		(6 "In2.Cu" signal "L3")
		(8 "In3.Cu" signal "L4GND")
		(10 "In4.Cu" signal "L5")
		(12 "In5.Cu" signal "L6VCC")
		(14 "In6.Cu" signal "L7VCC")
		(16 "In7.Cu" signal "L8")
		(18 "In8.Cu" signal "L9GND")
		(20 "In9.Cu" signal "L10")
		(22 "In10.Cu" signal "L11GND")
		(2 "B.Cu" signal "BOTTOM")
		(9 "F.Adhes" user "F.Adhesive")
		(11 "B.Adhes" user "B.Adhesive")
		(13 "F.Paste" user "Package Geometry/Pastemask Top")
		(15 "B.Paste" user "Package Geometry/Pastemask Bottom")
		(5 "F.SilkS" user "Ref Des/Silkscreen Top")
		(7 "B.SilkS" user "Ref Des/Silkscreen Bottom")
		(1 "F.Mask" user "Board Geometry/Soldermask Top")
		(3 "B.Mask" user "Board Geometry/Soldermask Bottom")
		(17 "Dwgs.User" user "User.Drawings")
		(19 "Cmts.User" user "User.Comments")
		(21 "Eco1.User" user "User.Eco1")
		(23 "Eco2.User" user "User.Eco2")
		(25 "Edge.Cuts" user "Board Geometry/Outline")
		(27 "Margin" user)
		(31 "F.CrtYd" user "Package Geometry/Place Bound Top")
		(29 "B.CrtYd" user "Package Geometry/Place Bound Bottom")
		(35 "F.Fab" user "Ref Des/Assembly Top")
		(33 "B.Fab" user "Ref Des/Assembly Bottom")
	)
	(footprint ""
		(layer "B.Cu")
		(at 190.292482 -233.753406 90)
		(property "Reference" "C678"
			(at 0 0 90)
			(layer "B.SilkS")
			(hide yes)
			(effects
				(font
					(size 1.27 1.27)
				)
				(justify mirror)
			)
		)
		(property "Value" "SCD1U25V3KX-GP"
			(at 0 -2.8194 90)
			(unlocked yes)
			(layer "B.Fab")
			(hide yes)
			(effects
				(font
					(size 1.016 1.016)
					(thickness 0.1524)
				)
				(justify mirror)
			)
		)
		(property "Device Type" "C603H36"
			(at 0 -4.3434 90)
			(unlocked yes)
			(layer "B.Fab")
			(hide yes)
			(effects
				(font
					(size 1.016 1.016)
					(thickness 0.1524)
				)
				(justify mirror)
			)
		)
		(duplicate_pad_numbers_are_jumpers no)
		(fp_line
			(start -0.508 0)
			(end 0.508 0)
			(stroke
				(width 0.2032)
				(type default)
			)
			(layer "B.SilkS")
		)
		(fp_rect
			(start 0.5842 1.3335)
			(end -0.5842 -1.3335)
			(stroke
				(width 0)
				(type default)
			)
			(fill no)
			(layer "B.CrtYd")
		)
		(fp_rect
			(start 0.5842 1.3335)
			(end -0.5842 -1.3335)
			(stroke
				(width 0)
				(type default)
			)
			(fill no)
			(layer "B.Fab")
		)
		(pad "1" smd custom
			(at 0 -0.762 270)
			(size 0.2159 0.2159)
			(layers "B.Cu" "B.Mask" "B.Paste")
			(net "P3V3_STBY_A")
			(options
				(clearance outline)
				(anchor circle)
			)
			(primitives
				(gr_poly
					(pts
						(arc
							(start -0.3302 0.4318)
							(mid -0.402042 0.402042)
							(end -0.4318 0.3302)
						)
						(arc
							(start -0.4318 -0.3302)
							(mid -0.402042 -0.402042)
							(end -0.3302 -0.4318)
						)
						(arc
							(start 0.3302 -0.4318)
							(mid 0.402042 -0.402042)
							(end 0.4318 -0.3302)
						)
						(arc
							(start 0.4318 0.3302)
							(mid 0.402042 0.402042)
							(end 0.3302 0.4318)
						)
					)
					(width 0)
					(fill yes)
				)
			)
		)
		(pad "2" smd custom
			(at 0 0.762 270)
			(size 0.2159 0.2159)
			(layers "B.Cu" "B.Mask" "B.Paste")
			(net "P3V3_STBY_VFB_R")
			(options
				(clearance outline)
				(anchor circle)
			)
			(primitives
				(gr_poly
					(pts
						(arc
							(start -0.3302 0.4318)
							(mid -0.402042 0.402042)
							(end -0.4318 0.3302)
						)
						(arc
							(start -0.4318 -0.3302)
							(mid -0.402042 -0.402042)
							(end -0.3302 -0.4318)
						)
						(arc
							(start 0.3302 -0.4318)
							(mid 0.402042 -0.402042)
							(end 0.4318 -0.3302)
						)
						(arc
							(start 0.4318 0.3302)
							(mid 0.402042 0.402042)
							(end 0.3302 0.4318)
						)
					)
					(width 0)
					(fill yes)
				)
			)
		)
	)
	(footprint ""
		(layer "B.Cu")
		(at 482.219 -237.109 -90)
		(property "Reference" "R1272"
			(at 0 0 90)
			(layer "B.SilkS")
			(hide yes)
			(effects
				(font
					(size 1.27 1.27)
				)
				(justify mirror)
			)
		)
		(property "Value" "100KR2F-L1-GP"
			(at -0.064008 -3.993896 270)
			(unlocked yes)
			(layer "B.Fab")
			(hide yes)
			(effects
				(font
					(size 1.016 1.016)
					(thickness 0.1524)
				)
				(justify mirror)
			)
		)
		(property "Device Type" "R402H16"
			(at -0.064008 -5.517896 270)
			(unlocked yes)
			(layer "B.Fab")
			(hide yes)
			(effects
				(font
					(size 1.016 1.016)
					(thickness 0.1524)
				)
				(justify mirror)
			)
		)
		(duplicate_pad_numbers_are_jumpers no)
		(fp_line
			(start -0.508 -0.9398)
			(end 0.508 -0.9398)
			(stroke
				(width 0.1524)
				(type default)
			)
			(layer "B.SilkS")
		)
		(fp_line
			(start 0.508 -0.9398)
			(end 0.508 0.9398)
			(stroke
				(width 0.1524)
				(type default)
			)
			(layer "B.SilkS")
		)
		(fp_rect
			(start 0.508 0.9398)
			(end -0.508 -0.9398)
			(stroke
				(width 0)
				(type default)
			)
			(fill no)
			(layer "B.CrtYd")
		)
		(fp_rect
			(start 0.508 0.9398)
			(end -0.508 -0.9398)
			(stroke
				(width 0)
				(type default)
			)
			(fill no)
			(layer "B.Fab")
		)
		(pad "1" smd custom
			(at 0 -0.4445 90)
			(size 0.1397 0.1397)
			(layers "B.Cu" "B.Mask" "B.Paste")
			(net "AGND_P5V_D")
			(options
				(clearance outline)
				(anchor circle)
			)
			(primitives
				(gr_poly
					(pts
						(arc
							(start -0.1778 0.2794)
							(mid -0.249642 0.249642)
							(end -0.2794 0.1778)
						)
						(arc
							(start -0.2794 -0.1778)
							(mid -0.249642 -0.249642)
							(end -0.1778 -0.2794)
						)
						(arc
							(start 0.1778 -0.2794)
							(mid 0.249642 -0.249642)
							(end 0.2794 -0.1778)
						)
						(arc
							(start 0.2794 0.1778)
							(mid 0.249642 0.249642)
							(end 0.1778 0.2794)
						)
					)
					(width 0)
					(fill yes)
				)
			)
		)
		(pad "2" smd custom
			(at 0 0.4445 90)
			(size 0.1397 0.1397)
			(layers "B.Cu" "B.Mask" "B.Paste")
			(net "P5V_D_MODE")
			(options
				(clearance outline)
				(anchor circle)
			)
			(primitives
				(gr_poly
					(pts
						(arc
							(start -0.1778 0.2794)
							(mid -0.249642 0.249642)
							(end -0.2794 0.1778)
						)
						(arc
							(start -0.2794 -0.1778)
							(mid -0.249642 -0.249642)
							(end -0.1778 -0.2794)
						)
						(arc
							(start 0.1778 -0.2794)
							(mid 0.249642 -0.249642)
							(end 0.2794 -0.1778)
						)
						(arc
							(start 0.2794 0.1778)
							(mid 0.249642 0.249642)
							(end 0.1778 0.2794)
						)
					)
					(width 0)
					(fill yes)
				)
			)
		)
	)
	(footprint ""
		(layer "B.Cu")
		(at 30.414214 -253.343664 180)
		(property "Reference" "R1221"
			(at 0 0 0)
			(layer "B.SilkS")
			(hide yes)
			(effects
				(font
					(size 1.27 1.27)
				)
				(justify mirror)
			)
		)
		(property "Value" "10KR2F-2-GP"
			(at -0.064008 -3.993896 180)
			(unlocked yes)
			(layer "B.Fab")
			(hide yes)
			(effects
				(font
					(size 1.016 1.016)
					(thickness 0.1524)
				)
				(justify mirror)
			)
		)
		(property "Device Type" "R402H16"
			(at -0.064008 -5.517896 180)
			(unlocked yes)
			(layer "B.Fab")
			(hide yes)
			(effects
				(font
					(size 1.016 1.016)
					(thickness 0.1524)
				)
				(justify mirror)
			)
		)
		(duplicate_pad_numbers_are_jumpers no)
		(fp_line
			(start 0.508 -0.9398)
			(end 0.508 0.9398)
			(stroke
				(width 0.1524)
				(type default)
			)
			(layer "B.SilkS")
		)
		(fp_line
			(start -0.508 -0.9398)
			(end 0.508 -0.9398)
			(stroke
				(width 0.1524)
				(type default)
			)
			(layer "B.SilkS")
		)
		(fp_rect
			(start 0.508 0.9398)
			(end -0.508 -0.9398)
			(stroke
				(width 0)
				(type default)
			)
			(fill no)
			(layer "B.CrtYd")
		)
		(fp_rect
			(start 0.508 0.9398)
			(end -0.508 -0.9398)
			(stroke
				(width 0)
				(type default)
			)
			(fill no)
			(layer "B.Fab")
		)
		(pad "1" smd custom
			(at 0 -0.4445)
			(size 0.1397 0.1397)
			(layers "B.Cu" "B.Mask" "B.Paste")
			(net "P5V_A_VFB")
			(options
				(clearance outline)
				(anchor circle)
			)
			(primitives
				(gr_poly
					(pts
						(arc
							(start -0.1778 0.2794)
							(mid -0.249642 0.249642)
							(end -0.2794 0.1778)
						)
						(arc
							(start -0.2794 -0.1778)
							(mid -0.249642 -0.249642)
							(end -0.1778 -0.2794)
						)
						(arc
							(start 0.1778 -0.2794)
							(mid 0.249642 -0.249642)
							(end 0.2794 -0.1778)
						)
						(arc
							(start 0.2794 0.1778)
							(mid 0.249642 0.249642)
							(end 0.1778 0.2794)
						)
					)
					(width 0)
					(fill yes)
				)
			)
		)
		(pad "2" smd custom
			(at 0 0.4445)
			(size 0.1397 0.1397)
			(layers "B.Cu" "B.Mask" "B.Paste")
			(net "AGND_P5V_A")
			(options
				(clearance outline)
				(anchor circle)
			)
			(primitives
				(gr_poly
					(pts
						(arc
							(start -0.1778 0.2794)
							(mid -0.249642 0.249642)
							(end -0.2794 0.1778)
						)
						(arc
							(start -0.2794 -0.1778)
							(mid -0.249642 -0.249642)
							(end -0.1778 -0.2794)
						)
						(arc
							(start 0.1778 -0.2794)
							(mid 0.249642 -0.249642)
							(end 0.2794 -0.1778)
						)
						(arc
							(start 0.2794 0.1778)
							(mid 0.249642 0.249642)
							(end 0.1778 0.2794)
						)
					)
					(width 0)
					(fill yes)
				)
			)
		)
	)
	(footprint ""
		(layer "B.Cu")
		(at 56.804814 -148.245576 180)
		(property "Reference" "C624"
			(at 0 0 0)
			(layer "B.SilkS")
			(hide yes)
			(effects
				(font
					(size 1.27 1.27)
				)
				(justify mirror)
			)
		)
		(property "Value" "SCD1U50V3KX-GP"
			(at 0 -2.8194 180)
			(unlocked yes)
			(layer "B.Fab")
			(hide yes)
			(effects
				(font
					(size 1.016 1.016)
					(thickness 0.1524)
				)
				(justify mirror)
			)
		)
		(property "Device Type" "C603H36"
			(at 0 -4.3434 180)
			(unlocked yes)
			(layer "B.Fab")
			(hide yes)
			(effects
				(font
					(size 1.016 1.016)
					(thickness 0.1524)
				)
				(justify mirror)
			)
		)
		(duplicate_pad_numbers_are_jumpers no)
		(fp_line
			(start -0.508 0)
			(end 0.508 0)
			(stroke
				(width 0.2032)
				(type default)
			)
			(layer "B.SilkS")
		)
		(fp_rect
			(start 0.5842 1.3335)
			(end -0.5842 -1.3335)
			(stroke
				(width 0)
				(type default)
			)
			(fill no)
			(layer "B.CrtYd")
		)
		(fp_rect
			(start 0.5842 1.3335)
			(end -0.5842 -1.3335)
			(stroke
				(width 0)
				(type default)
			)
			(fill no)
			(layer "B.Fab")
		)
		(pad "1" smd custom
			(at 0 -0.762)
			(size 0.2159 0.2159)
			(layers "B.Cu" "B.Mask" "B.Paste")
			(net "P5V_A_2")
			(options
				(clearance outline)
				(anchor circle)
			)
			(primitives
				(gr_poly
					(pts
						(arc
							(start -0.3302 0.4318)
							(mid -0.402042 0.402042)
							(end -0.4318 0.3302)
						)
						(arc
							(start -0.4318 -0.3302)
							(mid -0.402042 -0.402042)
							(end -0.3302 -0.4318)
						)
						(arc
							(start 0.3302 -0.4318)
							(mid 0.402042 -0.402042)
							(end 0.4318 -0.3302)
						)
						(arc
							(start 0.4318 0.3302)
							(mid 0.402042 0.402042)
							(end 0.3302 0.4318)
						)
					)
					(width 0)
					(fill yes)
				)
			)
		)
		(pad "2" smd custom
			(at 0 0.762)
			(size 0.2159 0.2159)
			(layers "B.Cu" "B.Mask" "B.Paste")
			(net "P5V_B_LL_R")
			(options
				(clearance outline)
				(anchor circle)
			)
			(primitives
				(gr_poly
					(pts
						(arc
							(start -0.3302 0.4318)
							(mid -0.402042 0.402042)
							(end -0.4318 0.3302)
						)
						(arc
							(start -0.4318 -0.3302)
							(mid -0.402042 -0.402042)
							(end -0.3302 -0.4318)
						)
						(arc
							(start 0.3302 -0.4318)
							(mid 0.402042 -0.402042)
							(end 0.4318 -0.3302)
						)
						(arc
							(start 0.4318 0.3302)
							(mid 0.402042 0.402042)
							(end 0.3302 0.4318)
						)
					)
					(width 0)
					(fill yes)
				)
			)
		)
	)
	(footprint ""
		(layer "B.Cu")
		(at 482.219 -235.966 -90)
		(property "Reference" "R1275"
			(at 0 0 90)
			(layer "B.SilkS")
			(hide yes)
			(effects
				(font
					(size 1.27 1.27)
				)
				(justify mirror)
			)
		)
		(property "Value" "143KR2F-L-1-GP"
			(at -0.064008 -3.993896 270)
			(unlocked yes)
			(layer "B.Fab")
			(hide yes)
			(effects
				(font
					(size 1.016 1.016)
					(thickness 0.1524)
				)
				(justify mirror)
			)
		)
		(property "Device Type" "R402H16"
			(at -0.064008 -5.517896 270)
			(unlocked yes)
			(layer "B.Fab")
			(hide yes)
			(effects
				(font
					(size 1.016 1.016)
					(thickness 0.1524)
				)
				(justify mirror)
			)
		)
		(duplicate_pad_numbers_are_jumpers no)
		(fp_line
			(start -0.508 -0.9398)
			(end 0.508 -0.9398)
			(stroke
				(width 0.1524)
				(type default)
			)
			(layer "B.SilkS")
		)
		(fp_line
			(start 0.508 -0.9398)
			(end 0.508 0.9398)
			(stroke
				(width 0.1524)
				(type default)
			)
			(layer "B.SilkS")
		)
		(fp_rect
			(start 0.508 0.9398)
			(end -0.508 -0.9398)
			(stroke
				(width 0)
				(type default)
			)
			(fill no)
			(layer "B.CrtYd")
		)
		(fp_rect
			(start 0.508 0.9398)
			(end -0.508 -0.9398)
			(stroke
				(width 0)
				(type default)
			)
			(fill no)
			(layer "B.Fab")
		)
		(pad "1" smd custom
			(at 0 -0.4445 90)
			(size 0.1397 0.1397)
			(layers "B.Cu" "B.Mask" "B.Paste")
			(net "AGND_P5V_D")
			(options
				(clearance outline)
				(anchor circle)
			)
			(primitives
				(gr_poly
					(pts
						(arc
							(start -0.1778 0.2794)
							(mid -0.249642 0.249642)
							(end -0.2794 0.1778)
						)
						(arc
							(start -0.2794 -0.1778)
							(mid -0.249642 -0.249642)
							(end -0.1778 -0.2794)
						)
						(arc
							(start 0.1778 -0.2794)
							(mid 0.249642 -0.249642)
							(end 0.2794 -0.1778)
						)
						(arc
							(start 0.2794 0.1778)
							(mid 0.249642 0.249642)
							(end 0.1778 0.2794)
						)
					)
					(width 0)
					(fill yes)
				)
			)
		)
		(pad "2" smd custom
			(at 0 0.4445 90)
			(size 0.1397 0.1397)
			(layers "B.Cu" "B.Mask" "B.Paste")
			(net "P5V_D_TRIP")
			(options
				(clearance outline)
				(anchor circle)
			)
			(primitives
				(gr_poly
					(pts
						(arc
							(start -0.1778 0.2794)
							(mid -0.249642 0.249642)
							(end -0.2794 0.1778)
						)
						(arc
							(start -0.2794 -0.1778)
							(mid -0.249642 -0.249642)
							(end -0.1778 -0.2794)
						)
						(arc
							(start 0.1778 -0.2794)
							(mid 0.249642 -0.249642)
							(end 0.2794 -0.1778)
						)
						(arc
							(start 0.2794 0.1778)
							(mid 0.249642 0.249642)
							(end 0.1778 0.2794)
						)
					)
					(width 0)
					(fill yes)
				)
			)
		)
	)
	(footprint ""
		(layer "B.Cu")
		(at 178.786282 -232.077006 180)
		(property "Reference" "C677"
			(at 0 0 0)
			(layer "B.SilkS")
			(hide yes)
			(effects
				(font
					(size 1.27 1.27)
				)
				(justify mirror)
			)
		)
		(property "Value" "SC2200P50V2KX-2GP"
			(at -1.1811 -2.7051 180)
			(unlocked yes)
			(layer "B.Fab")
			(hide yes)
			(effects
				(font
					(size 1.016 1.016)
					(thickness 0.1524)
				)
				(justify mirror)
			)
		)
		(property "Device Type" "C402H22"
			(at -1.1811 -4.2291 180)
			(unlocked yes)
			(layer "B.Fab")
			(hide yes)
			(effects
				(font
					(size 1.016 1.016)
					(thickness 0.1524)
				)
				(justify mirror)
			)
		)
		(duplicate_pad_numbers_are_jumpers no)
		(fp_rect
			(start 0.4318 0.9525)
			(end -0.4318 -0.9525)
			(stroke
				(width 0)
				(type default)
			)
			(fill no)
			(layer "B.CrtYd")
		)
		(fp_rect
			(start 0.4318 0.9525)
			(end -0.4318 -0.9525)
			(stroke
				(width 0)
				(type default)
			)
			(fill no)
			(layer "B.Fab")
		)
		(pad "1" smd custom
			(at 0 -0.4445)
			(size 0.1524 0.1524)
			(layers "B.Cu" "B.Mask" "B.Paste")
			(net "P3V3_STBY_SW")
			(options
				(clearance outline)
				(anchor circle)
			)
			(primitives
				(gr_poly
					(pts
						(arc
							(start 0.3048 0.2032)
							(mid 0.275042 0.275042)
							(end 0.2032 0.3048)
						)
						(arc
							(start -0.2032 0.3048)
							(mid -0.275042 0.275042)
							(end -0.3048 0.2032)
						)
						(arc
							(start -0.3048 -0.2032)
							(mid -0.275042 -0.275042)
							(end -0.2032 -0.3048)
						)
						(arc
							(start 0.2032 -0.3048)
							(mid 0.275042 -0.275042)
							(end 0.3048 -0.2032)
						)
					)
					(width 0)
					(fill yes)
				)
			)
		)
		(pad "2" smd custom
			(at 0 0.4445)
			(size 0.1524 0.1524)
			(layers "B.Cu" "B.Mask" "B.Paste")
			(net "P3V3_STBY_SNB")
			(options
				(clearance outline)
				(anchor circle)
			)
			(primitives
				(gr_poly
					(pts
						(arc
							(start 0.3048 0.2032)
							(mid 0.275042 0.275042)
							(end 0.2032 0.3048)
						)
						(arc
							(start -0.2032 0.3048)
							(mid -0.275042 0.275042)
							(end -0.3048 0.2032)
						)
						(arc
							(start -0.3048 -0.2032)
							(mid -0.275042 -0.275042)
							(end -0.2032 -0.3048)
						)
						(arc
							(start 0.2032 -0.3048)
							(mid 0.275042 -0.275042)
							(end 0.3048 -0.2032)
						)
					)
					(width 0)
					(fill yes)
				)
			)
		)
	)
	(footprint ""
		(layer "B.Cu")
		(at 183.082692 -239.238028 180)
		(property "Reference" "C685"
			(at 0 0 0)
			(layer "B.SilkS")
			(hide yes)
			(effects
				(font
					(size 1.27 1.27)
				)
				(justify mirror)
			)
		)
		(property "Value" "SC10U6D3V5KX-4GP"
			(at 0.0762 -6.1214 180)
			(unlocked yes)
			(layer "B.Fab")
			(hide yes)
			(effects
				(font
					(size 1.016 1.016)
					(thickness 0.1524)
				)
				(justify mirror)
			)
		)
		(property "Device Type" "C805H58"
			(at 0.0762 -8.1534 180)
			(unlocked yes)
			(layer "B.Fab")
			(hide yes)
			(effects
				(font
					(size 1.016 1.016)
					(thickness 0.1524)
				)
				(justify mirror)
			)
		)
		(duplicate_pad_numbers_are_jumpers no)
		(fp_line
			(start -0.635 0)
			(end 0.635 0)
			(stroke
				(width 0.508)
				(type default)
			)
			(layer "B.SilkS")
		)
		(fp_rect
			(start 0.9652 1.778)
			(end -0.9652 -1.778)
			(stroke
				(width 0)
				(type default)
			)
			(fill no)
			(layer "B.CrtYd")
		)
		(fp_poly
			(pts
				(xy 0.9652 -1.778) (xy -0.9652 -1.778) (xy -0.9652 1.778) (xy 0.9652 1.778)
			)
			(stroke
				(width 0)
				(type default)
			)
			(fill no)
			(layer "B.Fab")
		)
		(pad "1" smd rect
			(at 0 -0.9652)
			(size 1.397 1.143)
			(layers "B.Cu" "B.Mask" "B.Paste")
			(net "P3V3_STBY_A")
		)
		(pad "2" smd rect
			(at 0 0.9652)
			(size 1.397 1.143)
			(layers "B.Cu" "B.Mask" "B.Paste")
			(net "GND")
		)
	)
	(footprint ""
		(layer "B.Cu")
		(at 220.175328 -100.6856 -90)
		(property "Reference" "C31"
			(at 0 0 90)
			(layer "B.SilkS")
			(hide yes)
			(effects
				(font
					(size 1.27 1.27)
				)
				(justify mirror)
			)
		)
		(property "Value" "SC2D2U25V5KX-2-GP"
			(at 0.0762 -6.1214 270)
			(unlocked yes)
			(layer "B.Fab")
			(hide yes)
			(effects
				(font
					(size 1.016 1.016)
					(thickness 0.1524)
				)
				(justify mirror)
			)
		)
		(property "Device Type" "C805H54"
			(at 0.0762 -8.1534 270)
			(unlocked yes)
			(layer "B.Fab")
			(hide yes)
			(effects
				(font
					(size 1.016 1.016)
					(thickness 0.1524)
				)
				(justify mirror)
			)
		)
		(duplicate_pad_numbers_are_jumpers no)
		(fp_line
			(start -0.635 0)
			(end 0.635 0)
			(stroke
				(width 0.508)
				(type default)
			)
			(layer "B.SilkS")
		)
		(fp_rect
			(start 0.9652 1.778)
			(end -0.9652 -1.778)
			(stroke
				(width 0)
				(type default)
			)
			(fill no)
			(layer "B.CrtYd")
		)
		(fp_poly
			(pts
				(xy 0.9652 -1.778) (xy -0.9652 -1.778) (xy -0.9652 1.778) (xy 0.9652 1.778)
			)
			(stroke
				(width 0)
				(type default)
			)
			(fill no)
			(layer "B.Fab")
		)
		(pad "1" smd rect
			(at 0 -0.9652 90)
			(size 1.397 1.143)
			(layers "B.Cu" "B.Mask" "B.Paste")
			(net "P12V_A_COMP")
		)
		(pad "2" smd rect
			(at 0 0.9652 90)
			(size 1.397 1.143)
			(layers "B.Cu" "B.Mask" "B.Paste")
			(net "GND")
		)
	)
)
